# Primary and Alternate BOM of B91.01110.0038_IOM IOC.xls — Sheet0 (bom)
| Part Number | B91.01110.0038 |  |  |  |  |  |  |  |  |  |  |  |  |
| Revision | D |  |  |  |  |  |  |  |  |  |  |  |  |
| Sequence | 1 |  |  |  |  |  |  |  |  |  |  |  |  |
| Description | BRYCE CANYON IOM IOC PD P-2 MAIN |  |  |  |  |  |  |  |  |  |  |  |  |
| Project Code | BPD011010001 |  |  |  |  |  |  |  |  |  |  |  |  |
| Latest Revision? | YES |  |  |  |  |  |  |  |  |  |  |  |  |
| PDM BOM List |  |  |  |  |  |  |  |  |  |  |  |  |  |
| Level | Parent Number | Part Number | Description | Green Factor | Manufacturer | Manufacturer Part Number | Source | BOM Usage | M/P Code | S/D | Qty | UoM | Location |
| 1 | B91.01110.0038 | B55.01107.0011 | BRYCE CANYON IOM IOC PD P-2 MAIN(D) | R2; |  |  |  | M | Manufacture |  | 1 | PCS |  |
| 2 | B55.01107.0011 | 020.80074.0036 | CONN CTR 36P 10112626-101LF MINI-SAS HD | R2_SA;HF_SA; | FCI | 10112626-101LF | Single |  | Purchase | DIP | 2 | PCS | EXT1 EXT2 |
| 2 | B55.01107.0011 | 020.80818.0001 | CONN SIGNAL XCEDE JX410-50824_REVA | R2_SA; | AMPHENOL | JX410-50824_RevA | Single |  | Purchase | DIP | 1 | PCS | CN1 |
| 2 | B55.01107.0011 | 022.10005.06S1 | SKT USB 3.0 9P GSB31D13001HHR, PA10T | R2_SA;HF_SA; | AMPHENOL | GSB31D13001HHR | Single |  | Purchase | DIP | 1 | PCS | USB1 |
| 2 | B55.01107.0011 | 022.40001.0311 | SW TACT 4P DTSA-65R-Q,PA66/PA6T | R2_SA;HF_SA; | DIPTRONICS | DTSA-65R-Q | Single |  | Purchase | DIP | 1 | PCS | PWR1 |
| 2 | B55.01107.0011 | 022.40001.0A71 | SW TACT 4P DTSA-63K-Q-T/R(566)(766),PA9T | R2_SA;HF_SA; | DIPTRONICS | DTSA-63K-Q-T/R(566)(766) | Single |  | Purchase | DIP | 1 | PCS | RST1 |
| 2 | B55.01107.0011 | 06.WP130.14A | LED BLUE/YELLOW WP130WDT-TD88 3P DIP | R2_SA;HF_SA; | KINGBRIGHT | WP130WDT-TD88 | Single |  | Purchase | DIP | 3 | PCS | LED2 LED3 LED7 |
| 2 | B55.01107.0011 | 086.6A322.04R5 | SCRW ROUND M2 L3 ZN | R2_SA;HF_SA; | DURABLE | 086.6A322.04R5 | Single |  | Purchase | DIP | 2 | PCS |  |
| 2 | B55.01107.0011 | 40.58D03.001 | LBL POLYIMIDE31.8*6.35 BARCODE | R2_SA;HF_SA;G_SA; | LABELJET | 40.58D03.001 | Single |  | Purchase | DIP | 2 | PCS |  |
| 2 | B55.01107.0011 | 40.6E727.001 | LBL 50X15MM BLANK WHITE POLYESTER | R2_SA;HF_SA; | WISTRON | 40.6E727.001 | Single |  | Purchase | DIP | 1 | PCS |  |
| 2 | B55.01107.0011 | 640.00X01.0001 | LBL 7X7MM  FOR SONIC | R2_SA;HF_SA; | WISTRON | 640.00X01.0001 | Single |  | Purchase | DIP | 1 | PCS |  |
| 2 | B55.01107.0011 | B34.01107.0001 | HSINK_60X60X6.5_PUSHPIN_PAD_ACKBAR | R2_SA;HF_SA; | CCI | B34.01107.0001 | Single |  | Purchase | DIP | 1 | PCS |  |
| 2 | B55.01107.0011 | B42.0110B.0001 | SPACE SUPPORT BRCA KY | R2_SA;HF_SA; | KANGYANG | MSPJ-5V0 | Single |  | Purchase | DIP | 2 | PCS |  |
| 2 | B55.01107.0011 | B42.0111K.1001 | CVR XCEDE SIGNAL JX410-50824 MP | R2_SA;HF_SA; | KANGYANG | COVER-16 | Multiple |  | Purchase | DIP | 1 | PCS |  |
| A(Alternative to previous component) | B55.01107.0011 | B42.0111K.0001 | CVR XCEDE SIGNAL JX410-50824 | R2_SA;HF_SA; | KANGYANG | COVER-16 |  |  | Purchase |  |  |  |  |
| 2 | B55.01107.0011 | B55.01107.M011 | BRYCE CANYON IOM IOC PD P-2 MAIN(S) | R2; |  |  |  | M | Manufacture | DIP | 1 | PCS |  |
| 3 | B55.01107.M011 | 020.F0528.0011 | CONN CTR 11P 91931-31111LF SMD | R2_SA;HF_SA; | FCI | 91931-31111LF | Single |  | Purchase | SMT | 1 | PCS | TPM1 |
| 3 | B55.01107.M011 | 064.18025.06DL | CHIP RES 18K F 1/16W 0402 | R2_SA;HF_SA;G_SA; | KOA;YAGEO | RK73H1ETQTP1802F;RC0402FR-0718KL | Multiple |  | Purchase | SMT | 1 | PCS | R367 |
| 3 | B55.01107.M011 | 064.20515.06DP | CHIP RES 2.05K F 1/16W 0402 | R2_SA;HF_SA;G_SA; | TAI;RALEC;YAGEO | RM04FTN2051;RTT022051FTH;RC0402FR-072K05L | Multiple |  | Purchase | SMT | 1 | PCS | R537 |
| 3 | B55.01107.M011 | 064.41215.06DS | CHIP RES 4.12K F 1/16W 0402 | R2_SA;HF_SA;G_SA; | YAGEO;WALSIN;KOA | RC0402FR-074K12L;WR04X4121FTL;RK73H1ETQTP4121F | Multiple |  | Purchase | SMT | 1 | PCS | R447 |
| 3 | B55.01107.M011 | 064.51015.06DS | CHIP RES 5.1K F 1/16W 0402 | R2_SA;HF_SA;G_SA; | YAGEO;WALSIN;KOA | RC0402FR-075K1L;WR04X5101FTL;RK73H1ETQTP5101F | Multiple |  | Purchase | SMT | 1 | PCS | R448 |
| 3 | B55.01107.M011 | 068.3R310.2091 | CHIP CHOKE 3.3U M PCMB053T-3R3MS | R2_SA;HF_SA; | CYNTEC | PCMB053T-3R3MS | Single |  | Purchase | SMT | 1 | PCS | L10 |
| 3 | B55.01107.M011 | 071.02500.M002 | IC VGA AST2500A2-GP 19X19 TFBGA 456P | R2_SA;HF_SA; | ASPEED | AST2500A2-GP | Single |  | Purchase | SMT | 1 | PCS | U2 |
| 3 | B55.01107.M011 | 071.09306.0A0I | IC SMBUS/I2C PCA9306DCTR SSOP8 | R2_SA;HF_SA; | TI | PCA9306DCTR | Multiple |  | Purchase | SMT | 2 | PCS | U43 U45 |
| A | B55.01107.M011 | 71.09306.00W | IC SMBUS/I2C PCA9306DP1 TSSOP 8P | R2_SA;HF_SA; | NXP | PCA9306DP1,125 |  |  | Purchase |  |  |  |  |
| 3 | B55.01107.M011 | 071.09555.000W | IC I/O EXPANDER TCA9555PWR TSSOP 24P | R2_SA;HF_SA; | TI | TCA9555PWR | Multiple |  | Purchase | SMT | 1 | PCS | U34 |
| A | B55.01107.M011 | 71.09555.B0W | IC IO PCA9555PWRG4 TSSOP 24P | R2_SA;HF_SA; | TI | PCA9555PWRG4 |  |  | Purchase |  |  |  |  |
| 3 | B55.01107.M011 | 072.40256.0A0U | IC SDRAM DDR4-2400 256M*16 MT40A256M16GE | R2_SA;HF_SA; | MICRON | MT40A256M16GE-083E:B | Single |  | Purchase | SMT | 1 | PCS | U28 |
| 3 | B55.01107.M011 | 073.03166.000B | IC ANALOG SWITCH NX3L1G66GW,125 TSSOP5 | R2_SA;HF_SA; | NXP | NX3L1G66GW,125 | Multiple |  | Purchase | SMT | 3 | PCS | U12 U15 U16 |
| A | B55.01107.M011 | 073.53166.0A0G | IC ANALOG SWITCH TS5A3166DCKR SC70 | R2_SA;HF_SA; | TI | TS5A3166DCKR |  |  | Purchase |  |  |  |  |
| 3 | B55.01107.M011 | 073.23157.0009 | IC A.S TS5A23157DGSR DGS 10P | R2_SA;HF_SA; | TI | TS5A23157DGSR | Multiple |  | Purchase | SMT | 1 | PCS | U33 |
| A | B55.01107.M011 | 073.52315.0009 | IC A.S TS5A23157TDGSRQ1 MSOP 10P | R2_SA;HF_SA; | TI | TS5A23157TDGSRQ1 |  |  | Purchase |  |  |  |  |
| A | B55.01107.M011 | 073.73157.0009 | IC A.S U7SB3157G-SM2-R MSOP 10P | R2_SA;HF_SA; | UTC | U7SB3157G-SM2-R |  |  | Purchase |  |  |  |  |
| 3 | B55.01107.M011 | 074.01278.0A7Z | IC SWAP CTRL ADM1278-2ACPZ-RL LFCSP 32P | R2_SA;HF_SA; | ADI | ADM1278-2ACPZ-RL | Single |  | Purchase | SMT | 1 | PCS | U35 |
| 3 | B55.01107.M011 | 075.00639.007C | IC FET MOS SSM6P39TU 6P, UF6 | R2_SA;HF_SA; | TOSHIBA | SSM6P39TU | Multiple |  | Purchase | SMT | 3 | PCS | Q205 Q206 Q28 |
| A | B55.01107.M011 | 84.06P39.03F | FET MOS SSM6P39TU PC UF6 | R2_SA;HF_SA; | TOSHIBA | SSM6P39TU |  |  | Purchase |  |  |  |  |
| 3 | B55.01107.M011 | 077.51571.0001 | CHIP CAP EL POLY 150U 6.3V M7343 ESR17 | R2_SA;HF_SA; | PANASONIC | EEJRX0J151R | Multiple |  | Purchase | SMT | 1 | PCS | C175 |
| A | B55.01107.M011 | 077.C1571.0011 | CHIP CAP POLY T 150U 6.3V M7343 ESR18 | R2_SA;HF_SA; | NECTOKIN | PSKV0J157M018C |  |  | Purchase |  |  |  |  |
| A | B55.01107.M011 | 77.C1571.16L | CHIP CAP POLY T 150U 6.3V M7343 | R2_SA;HF_SA; | PANASONIC | EEFSX0J151ER |  |  | Purchase |  |  |  |  |
| 3 | B55.01107.M011 | 078.1022S.022L | CHIP CAP C 1000P 2KV K1206 X7R | R2_SA;HF_SA; | MURATA;YAGEO | GR431BR7LA102KW66L;CC1206KKX7RDBB102 | Multiple |  | Purchase | SMT | 5 | PCS | C525 C526 C527 C528 C529 |
| 3 | B55.01107.M011 | 078.10321.02S1 | CHIP CAP C 0.01U 16V K0201 X7R | R2_SA;HF_SA;G_SA; | DARFON;MURATA;TAIYO;WALSIN;YAGEO;SAMSUNG | C0603X7R103KET;GRM033R71C103KE14D;EMK063B7103KP-F;0201B103K160CT;CC0201KRX7R7BB103;CL03B103KO3NNNC | Multiple |  | Purchase | SMT | 32 | PCS | C307 C308 C309 C310 C311 C312 C313 C314 C315 C316 C317 C318 C319 C320 C321 C322 C486 C487 C488 C489 C490 C491 C492 C493 C494 C495 C496 C497 C498 C499 C500 C501 |
| 3 | B55.01107.M011 | 078.10521.08F1 | CHIP CAP C 1UF 16V K 0402 X6S | R2_SA;HF_SA;G_SA; | MURATA;DARFON;YAGEO;TAIYO | GRM155C81C105KE11D;C1005X6S105KET;CC0402KRX6S7BB105;LMK105C6105KV-F | Multiple |  | Purchase | SMT | 18 | PCS | C10 C11 C12 C35 C390 C391 C392 C393 C394 C395 C461 C462 C463 C464 C465 C466 C524 C9 |
| 3 | B55.01107.M011 | 078.10620.08B1 | CHIP CAP C 10U 6.3V K0603 X6S | R2_SA;HF_SA; | MURATA | GRM188C80J106KA73D | Multiple |  | Purchase | SMT | 2 | PCS | C104 C115 |
| A | B55.01107.M011 | 078.10610.08B1 | CHIP CAP C 10UF 6.3V M 0603 X6S | R2_SA;HF_SA; | MURATA;SAMSUNG;DARFON;YAGEO;TAIYO | GRM188C80J106MA73D;CL10X106MQ8NNNC;C1608X6S106MCT;CC0603MRX6S5BB106;JMK107BC6106MA-T |  |  | Purchase |  |  |  |  |
| 3 | B55.01107.M011 | 078.10621.0211 | CHIP CAP C 10UF 16V K0805 X7R | R2_SA;HF_SA;G_SA; | SAMSUNG;YAGEO | CL21B106KOQNNNE;CC0805KKX7R7BB106 | Multiple |  | Purchase | SMT | 24 | PCS | C151 C152 C153 C154 C155 C164 C165 C166 C170 C171 C173 C176 C177 C204 C205 C269 C270 C271 C272 C273 C274 C275 C511 C512 |
| 3 | B55.01107.M011 | 078.22610.08B1 | CHIP CAP C 22U 6.3V M0603 X6S MP | R2_SA;HF_SA; | MURATA;DARFON;WALSIN;YAGEO | GRM188C80J226ME15D;C1608X6S226MCT;0603S226M6R3CT;CC0603MRX6S5BB226 | Multiple |  | Purchase | SMT | 8 | PCS | C330 C334 C338 C342 C346 C350 C356 C363 |
| 3 | B55.01107.M011 | 078.47522.0211 | CHIP CAP C 4.7U 25V K0805 X7R | R2_SA;HF_SA;G_SA; | DARFON;MURATA;SAMSUNG;TAIYO;WALSIN;YAGEO | C2012X7R475KFP;GRM21BR71E475KA73L;CL21B475KAFNNNE;TMK212AB7475KG-T;0805B475K250CT;CC0805KKX7R8BB475 | Multiple |  | Purchase | SMT | 7 | PCS | C106 C116 C157 C179 C63 C81 C89 |
| 3 | B55.01107.M011 | 082.20005.0001 | OSC 24MHZ 25PPM 15PF HSO321S SMD | R2_SA;HF_SA; | HARMONY | SSW024000E3CH-SR5 | Multiple |  | Purchase | SMT | 1 | PCS | OSC1 |
| A | B55.01107.M011 | 082.20005.0091 | OSC 24MHZ 15P 25PPM HXO-SC SMD | R2_SA;HF_SA; | HOSONIC | D3SX24E000005E |  |  | Purchase |  |  |  |  |
| 3 | B55.01107.M011 | 082.30005.0311 | XTAL 25MHZ 12P30PPM HSX211S SMD HARMONY | R2_SA;HF_SA; | HARMONY | X2C025000FC1H-HX | Multiple |  | Purchase | SMT | 1 | PCS | SX1 |
| A | B55.01107.M011 | 82.30020.I61 | XTAL 25MHZ 20PPM 12PF HCX-1AB SMD | R2_SA;HF_SA; | HOSONIC | E1AB25.0000F12D22 |  |  | Purchase |  |  |  |  |
| 3 | B55.01107.M011 | 083.5V0X1.00AF | DIODE ESD PESD5V0X1UAB,115 SOD523 | R2_SA;HF_SA; | NEXPERIA | PESD5V0X1UAB,115 | Single |  | Purchase | SMT | 2 | PCS | D2 D3 |
| 3 | B55.01107.M011 | 084.00925.003N | FET MOS PH0925CL,115 NC LFPAK 4P | R2_SA;HF_SA; | NXP | PH0925CL,115 | Single |  | Purchase | SMT | 1 | PCS | Q5 |
| 3 | B55.01107.M011 | 084.3K324.0031 | FET MOS NC SSM3K324R SOT-23F 3P | R2_SA;HF_SA; | TOSHIBA | SSM3K324R | Multiple |  | Purchase | SMT | 7 | PCS | Q14 Q15 Q21 Q22 Q24 Q27 Q9 |
| A | B55.01107.M011 | 084.06244.0031 | FET MOS IRLML6244TRPBF SOT-23 | R2_SA;HF_SA; | IR | IRLML6244TRPBF |  |  | Purchase |  |  |  |  |
| 3 | B55.01107.M011 | 087.71242.0465 | NUT TPM M3*0.5*L6 NI EVT | R2_SA;HF_SA; | ?? | 087.71242.0465 | Single |  | Purchase | SMT | 1 | PCS | NUT1 |
| 3 | B55.01107.M011 | 19-000387$AA | IC CTRL SAS3008C0-1-DB-500020657 FPBGA | R2_SA;HF_SA; | LSI | 500020657 | Single |  | Purchase | SMT | 1 | PCS | U1 |
| 3 | B55.01107.M011 | 20.F1354.120 | CONN CTR SMD 120P 61082-121402LF ,LCP | R2_SA;HF_SA; | FCI | 61082-121402LF | Multiple |  | Purchase | SMT | 1 | PCS | MEZZ1 |
| A | B55.01107.M011 | 020.F0249.0120 | CONN CTR 120P 5177985-5 SMD ,LCP | R2_SA;HF_SA; | TE | 5177985-5 |  |  | Purchase |  |  |  |  |
| 3 | B55.01107.M011 | 62.10089.021 | SKT SPI CONN ACA-SPI-006-K01 ,LCP | R2_SA;HF_SA; | LOTES | ACA-SPI-006-K01 | Single |  | Purchase | SMT | 2 | PCS | SKT1 SKT2 |
| 3 | B55.01107.M011 | 63.10234.1DL | CHIP RES 1K J 1/16W 0402 | R2_SA;HF_SA;G_SA; | TA-I;RALEC;CYNTEC;YAGEO;WALSIN | RM04JTN102 ; RTT02102JTH ; RR0510S-102-JN ; RC0402JR-071KL;WR04X102JTL | Multiple |  | Purchase | SMT | 1 | PCS | R449 |
| 3 | B55.01107.M011 | 63.10334.1DL | CHIP RES 10K J 1/16W 0402 | R2_SA;HF_SA;G_SA; | CYNTEC;RALEC;TA-I;WALSIN;YAGEO | RR0510S-103-JN;RTT02103JTH;RM04JTN103;WR04X103JTL;RC0402JR-0710KL | Multiple |  | Purchase | SMT | 1 | PCS | R722 |
| 3 | B55.01107.M011 | 63.10434.L1L | CHIP RES 100K J 1/16W 0402 13" REEL | R2_SA;HF_SA;G_SA; | YAGEO;RALEC;WALSIN;TAI | RC0402JR-13100KL;RTT02104JH5;WR04X104 JHL;RM04JLN104 | Multiple |  | Purchase | SMT | 3 | PCS | R453 R457 R461 |
| 3 | B55.01107.M011 | 63.12334.1DL | CHIP RES 12K J 1/16W 0402 | R2_SA;HF_SA;G_SA; | TA-I ; RALEC ; CYNTEC ; YAGEO | RM04JTN123 ; RTT02123JTH ; RR0510S-123-JN ; RC0402JR-0712KL | Multiple |  | Purchase | SMT | 1 | PCS | R28 |
| 3 | B55.01107.M011 | 63.22234.1DL | CHIP RES 2.2K J 1/16W 0402 | R2_SA;HF_SA;G_SA; | TA-I;RALEC;CYNTEC;YAGEO;WALSIN | RM04JTN222 ; RTT02222JTH ; RR0510S-222-JN ; RC0402JR-072K2L;WR04X222JTL | Multiple |  | Purchase | SMT | 8 | PCS | R266 R267 R268 R500 R501 R83 R86 R90 |
| 3 | B55.01107.M011 | 63.2R233.15L | CHIP RES 2.2 J 1/10W 0603 | R2_SA;HF_SA;G_SA; | TA-I ; RALEC ; YAGEO ; WALSIN | RM06JTN2R2 ; RTT032R2JTP ; RC0603JR-072R2L ; WR06X2R2JTL | Multiple |  | Purchase | SMT | 1 | PCS | R483 |
| 3 | B55.01107.M011 | 63.2R734.15L | CHIP RES 2.7 J 1/10W 0603 | R2_SA;HF_SA;G_SA; | TA-I ; RALEC ; YAGEO | RM06JTN2R7 ; RTT032R7JTP ; RC0603JR-072R7L | Multiple |  | Purchase | SMT | 1 | PCS | R466 |
| 3 | B55.01107.M011 | 63.30234.1DL | CHIP RES 3K J 1/16W 0402(ROHS) | R2_SA;HF_SA;G_SA; | TA-I;RALEC;CYNTEC;YAGEO;WALSIN | RM04JTN302 ; RTT02302JTH ; RR0510S-302-JN ; RC0402JR-073KL;WR04X302JTL | Multiple |  | Purchase | SMT | 1 | PCS | R625 |
| 3 | B55.01107.M011 | 63.33034.1DL | CHIP RES 33 J 1/16W 0402 | R2_SA;HF_SA;G_SA; | TA-I;RALEC;CYNTEC;YAGEO;WALSIN | RM04JTN330 ; RTT02330JTH ; RR0510S-330-JN ; RC0402JR-0733RL;WR04X330JTL | Multiple |  | Purchase | SMT | 3 | PCS | R306 R763 R780 |
| 3 | B55.01107.M011 | 63.33234.1DL | CHIP RES 3.3K J 1/16W 0402 | R2_SA;HF_SA;G_SA; | TA-I;RALEC;CYNTEC;YAGEO;WALSIN | RM04JTN332;RTT02332JTH;RR-0510S-332-JN;RC0402JR-073K3L;WR04X332JTL | Multiple |  | Purchase | SMT | 1 | PCS | R468 |
| 3 | B55.01107.M011 | 63.82234.1DL | CHIP RES 8.2K J 1/16W 0402 | R2_SA;HF_SA;G_SA; | TA-I;RALEC;CYNTEC;YAGEO;WALSIN | RM04JTN822 ; RTT02822JTH ; RR0510S-822-JN ; RC0402JR-078K2L;WR04X822JTL | Multiple |  | Purchase | SMT | 7 | PCS | R136 R137 R138 R139 R338 R340 R65 |
| 3 | B55.01107.M011 | 63.R0031.16L | CHIP RES 0 J 1/8W 0805 | R2_SA;HF_SA;G_SA; | TAI;RALEC;YAGEO;WALSIN | RM10JTN0 ; RTT05000JTP ; RC0805JR-070RL ; WR08X000PTL | Multiple |  | Purchase | SMT | 6 | PCS | R504 R529 R536 R543 R709 R710 |
| 3 | B55.01107.M011 | 63.R0032.11L | CHIP RES 0 J 1/4W 1206 (ROHS) | R2_SA;HF_SA;G_SA; | TA-I ; RALEC ; YAGEO; WALSIN | RM12JTN0 ; RTT06000JTP ; RC1206JR-070RL; WR12X000 PTL | Multiple |  | Purchase | SMT | 4 | PCS | R479 R480 R481 R512 |
| 3 | B55.01107.M011 | 63.R0034.1DL | CHIP RES 0 J 1/16W 0402 | R2_SA;HF_SA;G_SA; | TAI;RALEC;CYNTEC;YAGEO;WALSIN | RM04JTN0;RTT02000JTH;RR0510X-000-XN;RC0402JR-070RL;WR04X000PTL | Multiple |  | Purchase | SMT | 157 | PCS | R10 R100 R123 R124 R127 R128 R129 R130 R131 R132 R14 R15 R151 R152 R153 R154 R155 R156 R157 R158 R159 R160 R161 R162 R163 R164 R165 R166 R167 R168 R169 R170 R171 R172 R173 R174 R175 R176 R177 R178 R239 R26 R278 R279 R281 R286 R288 R289 R290 R291 R292 R293 R294 R295 R297 R298 R301 R302 R312 R314 R316 R317 R318 R319 R320 R321 R322 R325 R326 R328 R329 R333 R334 R335 R342 R343 R344 R349 R350 R356 R368 R38 R4 R417 R418 R419 R426 R427 R436 R452 R459 R46 R460 R485 R498 R5 R508 R510 R516 R517 R522 R533 R535 R54 R540 R542 R547 R549 R558 R571 R602 R606 R607 R608 R609 R613 R614 R615 R617 R651 R691 R692 R693 R694 R7 R711 R712 R713 R714 R715 R717 R718 R719 R720 R724 R727 R731 R732 R736 R74 R768 R769 R770 R771 R772 R773 R787 R788 R795 R796 R797 R8 R9 R92 R96 R98 R99 |
| 3 | B55.01107.M011 | 64.10006.6DL | CHIP RES 100 D 1/16W 0402 | R2_SA;HF_SA;G_SA; | RALEC;TAI;CYNTEC;YAGEO | RTT021000DTH;RM04DTN1000;RR0510P-101-DN;RC0402DR-07100RL | Multiple |  | Purchase | SMT | 2 | PCS | R432 R434 |
| 3 | B55.01107.M011 | 64.10015.6DL | CHIP RES 1K F 1/16W 0402 | R2_SA;HF_SA;G_SA; | TA-I;RALEC;CYNTEC;YAGEO;WALSIN | RM04FTN1001 ; RTT021001FTH ; RR0510S-102-FN ; RC0402FR-071KL;WR04X1001FTL | Multiple |  | Purchase | SMT | 20 | PCS | R198 R199 R404 R405 R406 R408 R410 R412 R414 R415 R503 R528 R695 R696 R730 R735 R746 R774 R776 R779 |
| 3 | B55.01107.M011 | 64.10016.6DL | CHIP RES 1K D 1/16W 0402 | R2_SA;HF_SA;G_SA; | RALEC ; CYNTEC ; TA-I ; YAGEO | RTT021001DTH ; RR0510Q-102-DN ; RM04DTN1001 ; RT0402DRE071KL | Multiple |  | Purchase | SMT | 2 | PCS | R141 R143 |
| 3 | B55.01107.M011 | 64.10025.6DL | CHIP RES 10K F 1/16W 0402 | R2_SA;HF_SA;G_SA; | TA-I;RALEC;CYNTEC;YAGEO;WALSIN | RM04FTN1002 ; RTT021002FTH ; RR0510S-103-FN ; RC0402FR-0710KL;WR04X1002FTL | Multiple |  | Purchase | SMT | 72 | PCS | R24 R305 R307 R315 R351 R358 R359 R360 R361 R433 R467 R478 R487 R49 R499 R507 R513 R518 R525 R532 R539 R546 R553 R559 R56 R561 R568 R572 R573 R598 R618 R624 R626 R64 R645 R646 R647 R648 R649 R650 R652 R653 R654 R655 R656 R657 R660 R661 R662 R663 R664 R665 R666 R668 R669 R671 R672 R673 R674 R675 R676 R677 R678 R708 R72 R729 R742 R747 R78 R783 R784 R82 |
| 3 | B55.01107.M011 | 64.10035.6DL | CHIP RES 100K F 1/16W 0402 | R2_SA;HF_SA;G_SA; | TA-I;RALEC;CYNTEC;YAGEO;WALSIN | RM04FTN1003 ; RTT021003FTH ; RR0510S-104-FN ; RC0402FR-07100KL;WR04X1003FTL | Multiple |  | Purchase | SMT | 14 | PCS | R140 R146 R147 R148 R149 R275 R437 R562 R610 R688 R743 R80 R85 R88 |
| 3 | B55.01107.M011 | 64.10045.6DL | CHIP RES 1M F 1/16W 0402 | R2_SA;HF_SA;G_SA; | TA-I;RALEC;CYNTEC;YAGEO;WALSIN | RM04FTN1004;RTT021004FTH;RR0510S-105-FN;RC0402FR-071ML;WR04X1004FTL | Multiple |  | Purchase | SMT | 7 | PCS | R27 R37 R39 R44 R45 R47 R502 |
| 3 | B55.01107.M011 | 64.10R05.16L | CHIP RES 10 F 1/8W 0805(ROHS) | R2_SA;HF_SA;G_SA; | TAI;YAGEO;RALEC | RM10FTN10R0;RC0805FR-0710RL;RTT0510R0FTP | Multiple |  | Purchase | SMT | 1 | PCS | R450 |
| 3 | B55.01107.M011 | 64.10R05.55L | CHIP RES 10 F 1/10W 0603 | R2_SA;HF_SA;G_SA; | TA-I;RALEC;YAGEO;WALSIN | RM06FTN10R0 ; RTT0310R0FTP ; RC0603FR-0710RL;WR06X10R0FTL | Multiple |  | Purchase | SMT | 3 | PCS | R473 R489 R514 |
| 3 | B55.01107.M011 | 64.10R05.6DL | CHIP RES 10 F 1/16W 0402 | R2_SA;HF_SA;G_SA; | TAI;RALEC;CYNTEC;YAGEO;WALSIN | RM04FTN10R0;RTT0210R0FTH;RR0510S-100-FN;RC0402FR-0710RL;WR04X10R0FTL | Multiple |  | Purchase | SMT | 12 | PCS | R431 R440 R441 R442 R443 R679 R680 R681 R682 R683 R684 R685 |
| 3 | B55.01107.M011 | 64.11025.6DL | CHIP RES 11K F 1/16W 0402 | R2_SA;HF_SA;G_SA; | TA-I ; RALEC ; CYNTEC ; YAGEO;WALSIN | RM04FTN1102 ; RTT021102FTH ; RR0510S-1102-FN ; RC0402FR-0711KL;WR04X1102FTL | Multiple |  | Purchase | SMT | 2 | PCS | R439 R744 |
| 3 | B55.01107.M011 | 64.12005.55L | CHIP RES 120 F 1/10W 0603 | R2_SA;HF_SA;G_SA; | TA-I ; RALEC ; YAGEO | RM06FTN1200 ; RTT031200FTP ; RC0603FR-07120RL | Multiple |  | Purchase | SMT | 3 | PCS | R733 R737 R745 |
| 3 | B55.01107.M011 | 64.12005.6DL | CHIP RES 120 F 1/16W 0402 | R2_SA;HF_SA;G_SA; | TAI;RALEC;CYNTEC;YAGEO | RM04FTN1200;RTT021200FTH;RR0510S-121-FN;RC0402FR-07120RL | Multiple |  | Purchase | SMT | 48 | PCS | R209 R210 R211 R212 R215 R216 R217 R218 R220 R221 R222 R223 R225 R226 R227 R228 R229 R230 R231 R232 R233 R234 R235 R236 R237 R238 R240 R241 R242 R243 R244 R245 R246 R247 R248 R249 R250 R251 R252 R253 R254 R255 R256 R257 R258 R259 R260 R261 |
| 3 | B55.01107.M011 | 64.12115.6DL | CHIP RES 1.21K F 1/16W 0402 | R2_SA;HF_SA;G_SA; | TA-I;RALEC;CYNTEC;YAGEO;WALSIN | RM04FTN1211;RTT021211FTH;RR0510S-1211-FN;RC0402FR-071K21L;WR04X1211FTL | Multiple |  | Purchase | SMT | 1 | PCS | R557 |
| 3 | B55.01107.M011 | 64.13005.55L | CHIP RES 130 F 1/10W 0603 | R2_SA;HF_SA;G_SA; | TA-I ; RALEC ; YAGEO | RM06FTN1300 ; RTT031300FTP ; RC0603FR-07130RL | Multiple |  | Purchase | SMT | 3 | PCS | R800 R801 R817 |
| 3 | B55.01107.M011 | 64.13725.6DL | CHIP RES 13.7K F 1/16W 0402 | R2_SA;HF_SA;G_SA; | TA-I;RALEC;CYNTEC;YAGEO | RM04FTN1372;RTT021372FTH;RR0510S-1372-FN;RC0402FR-0713K7L | Multiple |  | Purchase | SMT | 1 | PCS | R515 |
| 3 | B55.01107.M011 | 64.14015.6DL | CHIP RES 1.4K F 1/16W 0402(ROHS) | R2_SA;HF_SA;G_SA; | CYNTEC;RALTEC;TAI;YAGEO | RR0510S-1401-FN;RTT021401FTH;RM04FTN1401;RC0402FR-071K4L | Multiple |  | Purchase | SMT | 2 | PCS | R407 R409 |
| 3 | B55.01107.M011 | 64.15005.6DL | CHIP RES 150 F 1/16W 0402 | R2_SA;HF_SA;G_SA; | TAI;RALEC;CYNTEC;YAGEO;WALSIN | RM04FTN1500 ; RTT021500FTH ; RR0510S-1500-FN ; RC0402FR-07150RL;WR04X1500FTL | Multiple |  | Purchase | SMT | 3 | PCS | R346 R622 R623 |
| 3 | B55.01107.M011 | 64.15025.6DL | CHIP RES 15K F 1/16W 0402 | R2_SA;HF_SA;G_SA; | TA-I;RALEC;CYNTEC;YAGEO | RM04FTN1502;RTT021502FTH;RR0510S-153-FN;RC0402FR-0715KL | Multiple |  | Purchase | SMT | 3 | PCS | R471 R491 R521 |
| 3 | B55.01107.M011 | 64.16915.6DL | CHIP RES 1.69K F 1/16W 0402 | R2_SA;HF_SA;G_SA; | TAI;RALEC;YAGEO;CYNTEC | RM04FTN1691;RTT021691FTH;RC0402FR-071K69L;RR0510S-1691-FN | Multiple |  | Purchase | SMT | 1 | PCS | R506 |
| 3 | B55.01107.M011 | 64.19125.6DL | CHIP RES 19.1K F 1/16W 0402 | R2_SA;HF_SA;G_SA; | TA-I;RALEC;CYNTEC;YAGEO | RM04FTN1912;RTT021912FTH;RR0510S-1912-FN;RC0402FR-0719K1L | Multiple |  | Purchase | SMT | 1 | PCS | R554 |
| 3 | B55.01107.M011 | 64.20005.6DL | CHIP RES 200 F 1/16W 0402 | R2_SA;HF_SA;G_SA; | TA-I;RALEC;CYNTEC;WALSIN;YAGEO | RM04FTN2000;RTT022000FTH;RR0510S-201-FN;WR04X2000FTL;RC0402FR-07200RL | Multiple |  | Purchase | SMT | 1 | PCS | R142 |
| 3 | B55.01107.M011 | 64.20025.6DL | CHIP RES 20K F 1/16W 0402 | R2_SA;HF_SA;G_SA; | TA-I;RALEC;CYNTEC;YAGEO;WALSIN | RM04FTN2002 ; RTT022002FTH ; RR0510S-203-FN ; RC0402FR-0720KL;WR04X2002FTL | Multiple |  | Purchase | SMT | 2 | PCS | R193 R194 |
| 3 | B55.01107.M011 | 64.20035.6DL | CHIP RES 200K F 1/16W 0402 | R2_SA;HF_SA;G_SA; | TA-I;RALEC;CYNTEC;YAGEO;WALSIN | RM04FTN2003 ; RTT022003FTH ; RR0510S-204-FN ; RC0402FR-07200KL;WR04X2003FTL | Multiple |  | Purchase | SMT | 2 | PCS | R470 R833 |
| 3 | B55.01107.M011 | 64.22015.6DL | CHIP RES 2.2K F 1/16W 0402 | R2_SA;HF_SA;G_SA; | TA-I;RALEC;CYNTEC;YAGEO | RM04FTN2201;RTT022201FTH;RR0510S-222-FN;RC0402FR-072K2L | Multiple |  | Purchase | SMT | 42 | PCS | R179 R180 R181 R182 R183 R184 R185 R186 R187 R188 R191 R192 R195 R196 R197 R200 R201 R202 R203 R204 R576 R577 R578 R579 R580 R581 R582 R583 R584 R585 R586 R587 R588 R589 R590 R591 R592 R593 R594 R595 R689 R690 |
| 3 | B55.01107.M011 | 64.22105.6DL | CHIP RES 221 F 1/16W 0402 | R2_SA;HF_SA;G_SA; | TA-I;RALEC;CYNTEC;YAGEO | RM04FTN2210;RTT022210FTH;RR0510S-2210-FN;RC0402FR-07221RL | Multiple |  | Purchase | SMT | 2 | PCS | R555 R565 |
| 3 | B55.01107.M011 | 64.22625.6DL | CHIP RES 22.6K F 1/16W 0402 | R2_SA;HF_SA;G_SA; | RALEC;CYNTEC;TA-I;YAGEO;WALSIN | RTT022262FTH ; RR0510S-2262-FN ; RM04FTN2262 ; RC0402FR-0722K6L;WR04X2262JTL | Multiple |  | Purchase | SMT | 1 | PCS | R462 |
| 3 | B55.01107.M011 | 64.24005.6DL | CHIP RES 240 F 1/16W 0402(ROHS | R2_SA;HF_SA;G_SA; | TA-I ; RALEC ; CYNTEC ; YAGEO | RM04FTN2400 ; RTT022400FTH ; RR0510S-241-FN ; RC0402FR-07240RL | Multiple |  | Purchase | SMT | 2 | PCS | R145 R219 |
| 3 | B55.01107.M011 | 64.24915.6DL | CHIP RES 2.49K F 1/16W 0402 | R2_SA;HF_SA;G_SA; | TA-I;RALEC;CYNTEC;YAGEO;WALSIN | RM04FTN2491;RTT022491FTH;RR0510S-2491-FN;RC0402FR-072K49L;WR04X2491FTL | Multiple |  | Purchase | SMT | 1 | PCS | R530 |
| 3 | B55.01107.M011 | 64.27015.6DL | CHIP RES 2.7K F 1/16W 0402 | R2_SA;HF_SA;G_SA; | TAI;RALEC;CYNTEC;YAGEO | RM04FTN2701;RTT022701FTH;RR0510S-2701-FN;RC0402FR-072K7L | Multiple |  | Purchase | SMT | 3 | PCS | R214 R413 R488 |
| 3 | B55.01107.M011 | 64.2R205.55L | CHIP RES 2.2 F 1/10W 0603 | R2_SA;HF_SA;G_SA; | TAI;YAGEO;RALEC;WALSIN | RM06FTN2R20;RC0603FR-072R2L;RTT032R20FTP;WR06W2R20FTL | Multiple |  | Purchase | SMT | 2 | PCS | R464 R511 |
| 3 | B55.01107.M011 | 64.30005.6DL | CHIP RES 300 F 1/16W 0402 | R2_SA;HF_SA;G_SA; | CYNTEC;RALEC;TAI;YAGEO | RR0510S-301-FN;RTT023000FTH;RM04FTN3000;RC0402FR-07300RL | Multiple |  | Purchase | SMT | 1 | PCS | R91 |
| 3 | B55.01107.M011 | 64.33005.6DL | CHIP RES 330 F 1/16W 0402 | R2_SA;HF_SA;G_SA; | CYNTEC;RALEC;TAI;YAGEO | RR0510S-331-FN;RTT023300FTH;RM04FTN3300;RC0402FR-07330RL | Multiple |  | Purchase | SMT | 2 | PCS | R402 R403 |
| 3 | B55.01107.M011 | 64.33R05.6DL | CHIP RES 33 F 1/16W 0402 | R2_SA;HF_SA;G_SA; | TA-I;RALEC;CYNTEC;YAGEO;WALSIN | RM04FTN33R0;RTT0233R0FTH;RR0510S-330-FN;RC0402FR-0733RL;WR04X33R0FTL | Multiple |  | Purchase | SMT | 9 | PCS | R270 R277 R280 R283 R284 R51 R52 R58 R59 |
| 3 | B55.01107.M011 | 64.33R25.6DL | CHIP RES 33.2 F 1/16W 0402 | R2_SA;HF_SA;G_SA; | TA-I;RALEC;CYNTEC;YAGEO | RM04FTN33R2;RTT0233R2FTH;RR0510S-33R2-FN;RC0402FR-0733R2L | Multiple |  | Purchase | SMT | 1 | PCS | R89 |
| 3 | B55.01107.M011 | 64.35715.6DL | CHIP RES 3.57K F 1/16W 0402 | R2_SA;HF_SA;G_SA; | TA-I;RALEC;CYNTEC;YAGEO | RM04FTN3571;RTT023571FTH;RR0510S-3571-FN;RC0402FR-073K57L | Multiple |  | Purchase | SMT | 1 | PCS | R505 |
| 3 | B55.01107.M011 | 64.38315.6DL | CHIP RES 3.83K F 1/16W 0402 | R2_SA;HF_SA;G_SA; | TA-I;RALEC;CYNTEC;YAGEO | RM04FTN3831;RTT023831FTH;RR0510S-3831-FN;RC0402FR-073K83L | Multiple |  | Purchase | SMT | 1 | PCS | R435 |
| 3 | B55.01107.M011 | 64.3R015.16L | CHIP RES 3.01 F 1/8W 0805 | R2_SA;HF_SA;G_SA; | TA-I;RALEC | RM10FTN3R01;RTT053R01FTP | Multiple |  | Purchase | SMT | 1 | PCS | R484 |
| 3 | B55.01107.M011 | 64.42215.6DL | CHIP RES 4.22K F 1/16W 0402 | R2_SA;HF_SA;G_SA; | YAGEO;TA-I;CYNTEC;RALEC | RC0402FR-074K22L;RM04FTN4221;RR0510S-4221-FN;RTT024221FTH | Multiple |  | Purchase | SMT | 1 | PCS | R544 |
| 3 | B55.01107.M011 | 64.44225.6DL | CHIP RES 44.2K F 1/16W 0402 | R2_SA;HF_SA;G_SA; | TAI;RALEC;CYNTEC;YAGEO;WALSIN | RM04FTN4422;RTT024422FTH;RR0510S-4422-FN;RC0402FR-0744K2L;WR04X4422FTL | Multiple |  | Purchase | SMT | 1 | PCS | R496 |
| 3 | B55.01107.M011 | 64.45305.6DL | CHIP RES 453 F 1/16W 0402 | R2_SA;HF_SA;G_SA; | TA-I;RALEC;CYNTEC;YAGEO;WALSIN | RM04FTN4530 ; RTT024530FTH ; RR0510S-4530-FN ; RC0402FR-07453RL;WR04X4530FTL | Multiple |  | Purchase | SMT | 1 | PCS | R566 |
| 3 | B55.01107.M011 | 64.45315.6DL | CHIP RES 4.53K F 1/16W 0402 | R2_SA;HF_SA;G_SA; | TA-I;RALEC;CYNTEC;YAGEO;WALSIN | RM04FTN4531 ; RTT024531FTH ; RR0510S-4531-FN ; RC0402FR-074K53L;WR04X4531FTL | Multiple |  | Purchase | SMT | 1 | PCS | R523 |
| 3 | B55.01107.M011 | 64.46415.6DL | CHIP RES 4.64K F 1/16W 0402 | R2_SA;HF_SA;G_SA; | RALEC;TAI;YAGEO;CYNTEC | RTT024641FTH;RM04FTN4641;RC0402FR-074K64L;RR0510S-4641-FN | Multiple |  | Purchase | SMT | 1 | PCS | R538 |
| 3 | B55.01107.M011 | 64.47015.6DL | CHIP RES 4.7K F 1/16W 0402 | R2_SA;HF_SA;G_SA; | TA-I;RALEC;CYNTEC;YAGEO;WALSIN | RM04FTN4701;RTT024701FTH;RR0510S-472-FN;RC0402FR-074K7L;WR04X4701FTL | Multiple |  | Purchase | SMT | 96 | PCS | R105 R20 R22 R23 R262 R263 R264 R265 R271 R276 R29 R299 R3 R30 R308 R31 R310 R313 R32 R324 R327 R33 R331 R337 R339 R34 R341 R35 R352 R353 R36 R369 R370 R375 R379 R383 R385 R386 R387 R394 R395 R396 R397 R398 R420 R422 R423 R424 R425 R48 R524 R526 R527 R550 R551 R552 R567 R596 R599 R601 R603 R604 R605 R616 R619 R620 R621 R627 R628 R629 R630 R631 R632 R633 R634 R635 R636 R637 R638 R639 R658 R659 R697 R701 R702 R703 R705 R706 R721 R723 R725 R726 R728 R738 R740 R84 |
| 3 | B55.01107.M011 | 64.47025.6DL | CHIP RES 47K F 1/16W 0402 | R2_SA;HF_SA;G_SA; | TA-I;RALEC;CYNTEC;YAGEO;WALSIN | RM04FTN4702;RTT024702FTH;RR0510S-473-FN;RC0402FR-0747KL;WR04X4702FTL | Multiple |  | Purchase | SMT | 3 | PCS | R303 R304 R76 |
| 3 | B55.01107.M011 | 64.47035.6DL | CHIP RES 470K F 1/16W 0402 | R2_SA;HF_SA;G_SA; | TA-I;RALEC;CYNTEC;YAGEO;WALSIN | RM04FTN4703;RTT024703FTH;RR0510S-474-FN;RC0402FR-07470KL;WR04X4703FTL | Multiple |  | Purchase | SMT | 1 | PCS | R79 |
| 3 | B55.01107.M011 | 64.47515.6DL | CHIP RES 4.75K F 1/16W 0402 | R2_SA;HF_SA;G_SA; | TA-I;RALEC;CYNTEC;YAGEO | RM04FTN4751;RTT024751FTH;RR0510S-4751-FN;RC0402FR-074K75L | Multiple |  | Purchase | SMT | 4 | PCS | R545 R71 R73 R81 |
| 3 | B55.01107.M011 | 64.47535.6DL | CHIP RES 475K F 1/16W 0402 | R2_SA;HF_SA;G_SA; | TA-I;RALEC;CYNTEC;YAGEO | RM04FTN4753;RTT024753FTH;RR0510S-4753-FN;RC0402FR-07475KL | Multiple |  | Purchase | SMT | 1 | PCS | R492 |
| 3 | B55.01107.M011 | 64.49905.6DL | CHIP RES 499 F 1/16W 0402 | R2_SA;HF_SA;G_SA; | TA-I ; RALEC ; CYNTEC ; YAGEO | RM04FTN4990 ; RTT024990FTH ; RR0510S-4990-FN ; RC0402FR-07499RL | Multiple |  | Purchase | SMT | 2 | PCS | R189 R190 |
| 3 | B55.01107.M011 | 64.49915.6DL | CHIP RES 4.99K F 1/16W 0402 | R2_SA;HF_SA;G_SA; | TA-I;RALEC;CYNTEC;YAGEO;WALSIN | RM04FTN4991 ; RTT024991FTH ; RR0510S-4991-FN ; RC0402FR-074K99L ; WR04X4991FTL | Multiple |  | Purchase | SMT | 1 | PCS | R531 |
| 3 | B55.01107.M011 | 64.49925.6DL | CHIP RES 49.9K F 1/16W 0402 | R2_SA;HF_SA;G_SA; | TA-I ; RALEC ; CYNTEC ; YAGEO ; WALSIN | RM04FTN4992 ; RTT024992FTH ; RR0510S-4992-FN ; RC0402FR-0749K9L ; WR04X4992FTL | Multiple |  | Purchase | SMT | 3 | PCS | R366 R445 R446 |
| 3 | B55.01107.M011 | 64.51025.6DL | CHIP RES 51K F 1/16W 0402 | R2_SA;HF_SA;G_SA; | TA-I ; RALEC ; CYNTEC ; YAGEO;WALSIN | RM04FTN5102 ; RTT025102FTH ; RR0510S-513-FN ; RC0402FR-0751KL;WR04X5102FTL | Multiple |  | Purchase | SMT | 1 | PCS | R454 |
| 3 | B55.01107.M011 | 64.57626.6DL | CHIP RES 57.6K D 1/16W 0402 | R2_SA;HF_SA;G_SA; | RALEC ; CYNTEC ; TA-I ; YAGEO | RTT025762DTH ; RR0510Q-5762-DN ; RM04DTN5762 ; RC0402DR-0757K6L | Multiple |  | Purchase | SMT | 2 | PCS | R475 R494 |
| 3 | B55.01107.M011 | 64.60R45.6DL | CHIP RES 60.4 F 1/16W 0402 | R2_SA;HF_SA;G_SA; | TA-I;RALEC;CYNTEC;YAGEO;WALSIN | RM04FTN60R4;RTT0260R4FTH;RR0510S-60R4-FN;RC0402FR-0760R4L;WR04X60R4FTL | Multiple |  | Purchase | SMT | 2 | PCS | R205 R206 |
| 3 | B55.01107.M011 | 64.69825.6DL | CHIP RES 69.8K F 1/16W 0402 | R2_SA;HF_SA;G_SA; | TA-I;RALEC;CYNTEC;YAGEO | RM04FTN6982;RTT026982FTH;RR0510S-6982-FN;RC0402FR-0769K8L | Multiple |  | Purchase | SMT | 1 | PCS | R560 |
| 3 | B55.01107.M011 | 64.73215.6DL | CHIP RES 7.32K F 1/16W 0402 | R2_SA;HF_SA;G_SA; | TA-I;RALEC;CYNTEC;YAGEO;WALSIN | RM04FTN7321;RTT027321FTH;RR0510S-7321-FN;RC0402FR-077K32L;WR04X7321FTL | Multiple |  | Purchase | SMT | 1 | PCS | R564 |
| 3 | B55.01107.M011 | 64.73225.6DL | CHIP RES 73.2K F 1/16W 0402 | R2_SA;HF_SA;G_SA; | TA-I;RALEC;CYNTEC;YAGEO;WALSIN | RM04FTN7322;RTT027322FTH;RR0510S-7322-FN;RC0402FR-0773K2L;WR04X7322FTL | Multiple |  | Purchase | SMT | 1 | PCS | R474 |
| 3 | B55.01107.M011 | 64.78715.6DL | CHIP RES 7.87K F 1/16W 0402 | R2_SA;HF_SA;G_SA; | TA-I;RALEC;CYNTEC;YAGEO | RM04FTN7871;RTT027871FTH;RR0510S-7871-FN;RC0402FR-077K87L | Multiple |  | Purchase | SMT | 1 | PCS | R401 |
| 3 | B55.01107.M011 | 64.86605.6DL | CHIP RES 866 F 0402 1/16W | R2_SA;HF_SA;G_SA; | RALEC;TA-I;YAGEO;WALSIN | RTT028660FTH;RM04FTN8660;RC0402FR-07866RL;WR04X8660FTL | Multiple |  | Purchase | SMT | 1 | PCS | R778 |
| 3 | B55.01107.M011 | 64.86625.6DL | CHIP RES 86.6K F 1/16W 0402 | R2_SA;HF_SA;G_SA; | TA-I;RALEC;CYNTEC;YAGEO | RM04FTN8662;RTT028662FTH;RR0510S-8662-FN;RC0402FR-0786K6L | Multiple |  | Purchase | SMT | 1 | PCS | R458 |
| 3 | B55.01107.M011 | 64.R0025.L1L | CHIP RES 0.002 F 1W 0612 | R2_SA;HF_SA; | CYNTEC | RL1632L4-R002-FN | Single |  | Purchase | SMT | 1 | PCS | R444 |
| 3 | B55.01107.M011 | 64.R5105.55L | CHIP RES 0.51 F 1/10W 0603 L/F | R2_SA;HF_SA;G_SA; | RALEC ; TA-I ; YAGEO ; WALSIN | RTT03R510FTP ; RL06FTNR510 ; RL0603FR-070R51L ; WW06XR510FTL | Multiple |  | Purchase | SMT | 2 | PCS | R686 R687 |
| 3 | B55.01107.M011 | 68.00084.771 | CHIP BEAD BLM41PG600SN1L MURAT | R2_SA;HF_SA; | MURATA | BLM41PG600SN1L | Multiple |  | Purchase | SMT | 1 | PCS | L11 |
| A | B55.01107.M011 | 68.00214.071 | CHIP BEAD HCB4516KF-600T60(LF) | R2_SA;HF_SA; | TAITECH | HCB4516KF-600T60 |  |  | Purchase |  |  |  |  |
| A | B55.01107.M011 | 68.00376.031 | CHIP BEAD BCMS451616A600 | R2_SA;HF_SA; | MAXECHO | BCMS451616A600 |  |  | Purchase |  |  |  |  |
| 3 | B55.01107.M011 | 68.00084.831 | CHIP BEAD BLM21PG220SN1D (LF) | R2_SA;HF_SA; | MURATA | BLM21PG220SN1D | Multiple |  | Purchase | SMT | 2 | PCS | L6 L8 |
| A | B55.01107.M011 | 68.00216.081 | CHIP BEAD HCB2012KF-220T60 | R2_SA;HF_SA; | TAITECH | HCB2012KF-220T60 |  |  | Purchase |  |  |  |  |
| 3 | B55.01107.M011 | 68.00084.A61 | CHIP BEAD BLM21PG300SN1D MURAT | R2_SA;HF_SA; | MURATA | BLM21PG300SN1D | Multiple |  | Purchase | SMT | 1 | PCS | L23 |
| A | B55.01107.M011 | 068.00002.0091 | CHIP BEAD BLM21SN300SN1D MURATA | R2_SA;HF_SA; | MURATA | BLM21SN300SN1D |  |  | Purchase |  |  |  |  |
| 3 | B55.01107.M011 | 68.00109.171 | CHIP BEAD MMZ2012S601ATA1N TDK | R2_SA;HF_SA; | TDK | MMZ2012S601ATA1N | Single |  | Purchase | SMT | 4 | PCS | L2 L3 L4 L5 |
| 3 | B55.01107.M011 | 68.00224.051 | CHIP BEAD MPZ2012S300AT TDK | R2_SA;HF_SA; | TDK | MPZ2012S300AT | Multiple |  | Purchase | SMT | 1 | PCS | L20 |
| A | B55.01107.M011 | 068.00002.0091 | CHIP BEAD BLM21SN300SN1D MURATA | R2_SA;HF_SA; | MURATA | BLM21SN300SN1D |  |  | Purchase |  |  |  |  |
| 3 | B55.01107.M011 | 68.00224.201 | CHIP BEAD MPZ2012S601AT TDK | R2_SA;HF_SA; | TDK | MPZ2012S601AT | Single |  | Purchase | SMT | 7 | PCS | L13 L14 L15 L16 L17 L18 L19 |
| 3 | B55.01107.M011 | 68.00395.001 | CHIP BEAD 0181 28F0181-1SR-10 | R2_SA;HF_SA; | LAIRD | 28F0181-1SR-10 | Single |  | Purchase | SMT | 1 | PCS | L21 |
| 3 | B55.01107.M011 | 68.3R310.20V | CHIP CHOKE 3.3UH PCMB063T-3R3MS | R2_SA;HF_SA; | CYNTEC | PCMB063T-3R3MS | Multiple |  | Purchase | SMT | 1 | PCS | L9 |
| A | B55.01107.M011 | 68.3R31A.10V | CHIP IND 3.3UH MMD-06CZ-3R3M-V | R2_SA;HF_SA;G_SA; | MAGLAYER | MMD-06CZ-3R3M-V1W |  |  | Purchase |  |  |  |  |
| 3 | B55.01107.M011 | 68.4R71A.20Q | CHIP CHOKE 4.7UH M PCMB104T-4R7MS | R2_SA;HF_SA; | CYNTEC | PCMB104T-4R7MS | Multiple |  | Purchase | SMT | 1 | PCS | L7 |
| A | B55.01107.M011 | 68.4R71D.10U | CHIP IND 4.7UH MMD-10DZ-4R7M-X2W | R2_SA;HF_SA; | MAGLAYER | MMD-10DZ-4R7M-X2W |  |  | Purchase |  |  |  |  |
| 3 | B55.01107.M011 | 68.R2410.20A | CHIP CHOKE 0.24UH PCME064T-R24MS1R007 | R2_SA;HF_SA; | CYNTEC | PCME064T-R24MS1R007 | Multiple |  | Purchase | SMT | 1 | PCS | L12 |
| A | B55.01107.M011 | 68.R2410.101 | CHIP IND 0.24UH MMD-06DZNR24MGC1W | R2_SA;HF_SA; | MAGLAYER | MMD-06DZNR24MGC1W |  |  | Purchase |  |  |  |  |
| 3 | B55.01107.M011 | 71.00551.00A | IC CLK BUF ICS551MLFT SOIC 8P | R2_SA;HF_SA; | IDT | ICS551MLFT | Single |  | Purchase | SMT | 1 | PCS | U30 |
| 3 | B55.01107.M011 | 71.02514.F03 | IC USB HUB USB2514B-AEZC-TR QFN 36P | R2_SA;HF_SA; | SMSC | USB2514B-AEZC-TR | Single |  | Purchase | SMT | 1 | PCS | U99 |
| 3 | B55.01107.M011 | 72.24C64.K01 | IC EEPROM M24C64-RMN6TP SOIC 8P | R2_SA;HF_SA; | STMICROELECTRONICS INC | M24C64-RMN6TP | Multiple |  | Purchase | SMT | 1 | PCS | U26 |
| A | B55.01107.M011 | 072.02464.0A01 | IC EEPROM FM24C64D-SO-T-G SOP 8P | R2_SA;HF_SA; | FUDAN | FM24C64D-SO-T-G |  |  | Purchase |  |  |  |  |
| 3 | B55.01107.M011 | 73.00102.007 | IC TRANSLATOR TXS0102DCUR VSSOP 8P | R2_SA;HF_SA; | TI | TXS0102DCUR | Multiple |  | Purchase | SMT | 1 | PCS | U44 |
| A | B55.01107.M011 | 71.09406.001 | IC I2C/SMBUS TCA9406DCUR US8 | R2_SA;HF_SA; | TI | TCA9406DCUR |  |  | Purchase |  |  |  |  |
| 3 | B55.01107.M011 | 73.01G07.01H | IC BUF SN74LVC1G07DCKRG4 DCK5P | R2_SA;HF_SA; | TI | SN74LVC1G07DCKRG4 | Multiple |  | Purchase | SMT | 1 | PCS | U9 |
| A | B55.01107.M011 | 73.01G07.AHG | IC SUF/DRI U74LVC1G07G-AL5-R SOT-353 | R2_SA;HF_SA; | UTC | U74LVC1G07G-AL5-R |  |  | Purchase |  |  |  |  |
| 3 | B55.01107.M011 | 73.01G07.EHH | IC CMOS 74LVC1G07DCKR SC70-5 | R2_SA;HF_SA; | TI | SN74LVC1G07DCKR | Multiple |  | Purchase | SMT | 1 | PCS | U95 |
| A | B55.01107.M011 | 73.01G07.0HG | IC CMOS 74LVC1G07GW,125 SOT353-1 | R2_SA;HF_SA; | NEXPERIA | 74LVC1G07GW,125 |  |  | Purchase |  |  |  |  |
| 3 | B55.01107.M011 | 73.01G08.L03 | IC CMOS SN74LVC1G08DCKR SC-70 | R2_SA;HF_SA;G_SA; | TI | SN74LVC1G08DCKR | Multiple |  | Purchase | SMT | 8 | PCS | U31 U36 U37 U46 U48 U49 U51 U52 |
| A | B55.01107.M011 | 073.7SZ08.000G | IC CMOS TC7SZ08FU,LJ(CT SSOP5-P-0.65A | R2_SA;HF_SA; | TOSHIBA | TC7SZ08FU,LJ(CT |  |  | Purchase |  |  |  |  |
| A | B55.01107.M011 | 73.01G08.DHG | IC CMOS SN74LVC1G08DCKRG4 DCK | R2_SA;HF_SA;G_SA; | TI | SN74LVC1G08DCKRG4 |  |  | Purchase |  |  |  |  |
| 3 | B55.01107.M011 | 73.01G14.AHG | IC CMOS SN74LVC1G14DBVR SOT-23 | R2_SA;HF_SA; | TI | SN74LVC1G14DBVR | Multiple |  | Purchase | SMT | 1 | PCS | U106 |
| A | B55.01107.M011 | 73.7SZ14.BAG | IC CMOS NC7SZ14M5X SOT-23-5 | R2_SA;HF_SA; | FAIRCHILD | NC7SZ14M5X |  |  | Purchase |  |  |  |  |
| 3 | B55.01107.M011 | 73.01G14.L05 | IC CMOS 74LVC1G14DCKR SC-70(GP | R2_SA;HF_SA;G_SA; | TI | SN74LVC1G14DCKR | Single |  | Purchase | SMT | 1 | PCS | U102 |
| 3 | B55.01107.M011 | 73.01G86.DHH | IC CMOS SN74LVC1G86DCKR SC70-5 | R2_SA;HF_SA; | TI | SN74LVC1G86DCKR | Multiple |  | Purchase | SMT | 2 | PCS | U47 U50 |
| A | B55.01107.M011 | 73.01G86.AHH | IC CMOS 74LVC1G86GW,125 SC-88A | R2_SA;HF_SA; | NXP | 74LVC1G86GW,125 |  |  | Purchase |  |  |  |  |
| 3 | B55.01107.M011 | 73.02G07.A2J | IC CMOS 74LVC2G07GW SOT-363 6P | R2_SA;HF_SA; | NXP | 74LVC2G07GW | Multiple |  | Purchase | SMT | 1 | PCS | U5 |
| A | B55.01107.M011 | 73.02G07.02J | IC CMOS SN74LVC2G07DCKR SC-70 | R2_SA;HF_SA; | TI | SN74LVC2G07DCKR |  |  | Purchase |  |  |  |  |
| A | B55.01107.M011 | 73.7WZ07.0AJ | IC CMOS NC7WZ07P6X SC70-6 | R2_SA;HF_SA; | FAIRCHILD | NC7WZ07P6X |  |  | Purchase |  |  |  |  |
| 3 | B55.01107.M011 | 73.03245.F0B | IC BUS SW SN74CBTLV3245APWR TSSOP 20P | R2_SA;HF_SA; | TI | SN74CBTLV3245APWR | Single |  | Purchase | SMT | 2 | PCS | U105 U107 |
| 3 | B55.01107.M011 | 73.07W74.0A7 | IC CMOS TC7WZ74FK SSOP8-P-0.50A | R2_SA;HF_SA; | TOSHIBA | TC7WZ74FK | Multiple |  | Purchase | SMT | 1 | PCS | U19 |
| A | B55.01107.M011 | 73.01G74.0HF | IC CMOS SN74LVC1G74DCUR VSSOP-8P | R2_SA;HF_SA; | TI | SN74LVC1G74DCUR |  |  | Purchase |  |  |  |  |
| 3 | B55.01107.M011 | 73.1G126.DHG | IC CMOS SN74LVC1G126DCKR SC70 | R2_SA;HF_SA; | TI | SN74LVC1G126DCKR | Multiple |  | Purchase | SMT | 4 | PCS | U100 U101 U103 U104 |
| A | B55.01107.M011 | 073.7S126.000G | IC CMOS TC7SZ126FU,LJ(CT SSOP5-P-0.65A | R2_SA;HF_SA; | TOSHIBA | TC7SZ126FU,LJ(CT |  |  | Purchase |  |  |  |  |
| A | B55.01107.M011 | 73.7S126.AAH | IC CMOS NC7SZ126P5X SC70-5 | R2_SA;HF_SA; | FAIRCHILD | NC7SZ126P5X |  |  | Purchase |  |  |  |  |
| 3 | B55.01107.M011 | 73.74126.BHB | IC BUF SN74LVC126APWR TSSOP14P | R2_SA;HF_SA; | TI | SN74LVC126APWR | Multiple |  | Purchase | SMT | 1 | PCS | U32 |
| A | B55.01107.M011 | 73.74126.0HB | IC CMOS 74LVC126APW,118 TSSOP14P | R2_SA;HF_SA; | NXP | 74LVC126APW,118 |  |  | Purchase |  |  |  |  |
| 3 | B55.01107.M011 | 74.00075.B79 | IC TEMP SENSOR TMP75AIDGKR MSOP 8P | R2_SA;HF_SA; | TI | TMP75AIDGKR | Multiple |  | Purchase | SMT | 1 | PCS | U27 |
| A | B55.01107.M011 | 074.00752.M001 | IC TEMP SEN STTS75DS2F MSOP 8P(FIONA) | R2_SA;HF_SA; | ST | STTS75DS2F |  |  | Purchase |  |  |  |  |
| 3 | B55.01107.M011 | 74.00235.033 | IC S.R VT235WFQX-ADJ QFN 19P | R2_SA;HF_SA; | VOLTERRA | VT235WFQX-ADJ | Single |  | Purchase | SMT | 1 | PCS | PU8 |
| 3 | B55.01107.M011 | 74.00331.A2F | IC V.R LMV331IDCKRG4 SC-70 5P | R2_SA;HF_SA; | TI | LMV331IDCKRG4 | Multiple |  | Purchase | SMT | 1 | PCS | U10 |
| A | B55.01107.M011 | 74.00331.I2F | IC V.C AZV331KSTR-G1 SC-70 5P | R2_SA;HF_SA; | BCD | AZV331KSTR-G1 |  |  | Purchase |  |  |  |  |
| 3 | B55.01107.M011 | 74.02065.07F | IC PWR SW TPS2065DBVT SOT-23 5P | R2_SA;HF_SA; | TI | TPS2065DBVT | Single |  | Purchase | SMT | 1 | PCS | U98 |
| 3 | B55.01107.M011 | 74.03808.073 | IC RESET TPS3808G18DRVR QFN 6P | R2_SA;HF_SA; | TI | TPS3808G18DRVR | Single |  | Purchase | SMT | 1 | PCS | U41 |
| 3 | B55.01107.M011 | 74.53312.073 | IC PWM CTRL TPS53312RGTR QFN 16P | R2_SA;HF_SA; | TI | TPS53312RGTR | Single |  | Purchase | SMT | 1 | PCS | PU4 |
| 3 | B55.01107.M011 | 74.53318.073 | IC PWR CTRL TPS53318DQPR QFN 22P | R2_SA;HF_SA; | TI | TPS53318DQPR | Single |  | Purchase | SMT | 2 | PCS | PU1 PU2 |
| 3 | B55.01107.M011 | 74.74801.A33 | IC LDO TPS74801RGW QFN 20P | R2_SA;HF_SA; | TI | TPS74801RGW | Single |  | Purchase | SMT | 4 | PCS | PU10 PU11 PU7 PU9 |
| 3 | B55.01107.M011 | 75.005V0.A77 | IC DIODE ESD PESD5V0S1BL,315 SOD882 | R2_SA;HF_SA; | NEXPERIA | PESD5V0S1BL,315 | Single |  | Purchase | SMT | 5 | PCS | D13 D14 D15 D16 D17 |
| 3 | B55.01107.M011 | 77.21071.02L | CHIP CAP POS 100U 16V M7343 ESR | R2_SA;HF_SA; | PANASONIC | 16TQC100MYF | Multiple |  | Purchase | SMT | 1 | PCS | C167 |
| A | B55.01107.M011 | 077.C1071.0001 | CHIP CAP T 100U 16V M 7343 ESR50 | R2_SA;HF_SA; | KEMET | T521V107M016ATE0507034 |  |  | Purchase |  |  |  |  |
| 3 | B55.01107.M011 | 77.21571.18L | CHIP CAP POS 150U 16V M7343 | R2_SA;HF_SA; | PANASONIC | 16TQC150MYF | Multiple |  | Purchase | SMT | 2 | PCS | C168 C325 |
| A | B55.01107.M011 | 077.C1571.0001 | CHIP CAPACITOR POLY T 150U 16V M 7343 | R2_SA;HF_SA; | KEMET | T521D157M016ATE055 |  |  | Purchase |  |  |  |  |
| 3 | B55.01107.M011 | 78.10134.1FL | CHIP CAP C 100P 50V J0402 NPO | R2_SA;HF_SA;G_SA; | AVX;DARFON;MURATA;PHYCOMP;SAMSUNG;TAIYO;WALSIN;YAGEO | CM05CG101J50AH;C1005NP0101JGT;GRM1555C1H101JA01D;223886915101;CL05C101JB5NNNC;UMK105CH101JV-F;0402N101J500CT;CC0402JRNPO9BN101 | Multiple |  | Purchase | SMT | 6 | PCS | C105 C206 C88 C91 C94 C96 |
| 3 | B55.01107.M011 | 78.10224.2FL | CHIP CAP C 1000P 50V K0402 X7R | R2_SA;R_SA;HF_SA;G_SA; | AVX;DARFON;MURATA;PHYCOMP;SAMSUNG;TAIYO;MURATA;AVX;YAGEO | CM05X7R102K50AH;C1005X7R102KGT;GRM155R71H102KA01D;223858715623;CL05B102KB5NNNC;UMK105B7102KV-F;WBM155R71H102KA01D;04025C102KAT2A;CC0402KRX7R9BB102 | Multiple |  | Purchase | SMT | 20 | PCS | C129 C162 C183 C287 C423 C424 C425 C426 C427 C428 C429 C430 C473 C474 C475 C476 C477 C478 C479 C480 |
| 3 | B55.01107.M011 | 78.10322.2FL | CHIP CAP C 0.01U 25V K0402 X7R | R2_SA;HF_SA;G_SA; | AVX;DARFON;MURATA;PHYCOMP;SAMSUNG;TAIYO;TDK;MURATA;YAGEO | 04023C103KAT2A;C1005X7R103KFT;GRM155R71E103KA01D;223891715636;CL05B103KA5NNNC;TMK105BJ103KV-F;C1005X7R1E103KT000F;WBM155R71E103KA01D;CC0402KRX7R8BB103 | Multiple |  | Purchase | SMT | 4 | PCS | C131 C284 C53 C76 |
| 3 | B55.01107.M011 | 78.10420.50L | CHIP CAP C 0.1U 6.3V K0201 X5R | R2_SA;HF_SA;G_SA; | MURATA;AVX;DARFON;WALSIN;MATSUKI;TAIYO;SAMSUNG;SAMSUNG;YAGEO | GRM033R60J104KE19D;02016D104KAT2A;C0603X5R104KCT;0201X104K6R3CT;MAG01X5R0J104K;JMK063BJ104KP-F;CL03A104KQ3NNNH;CL03A104KQ3NNNHC;CC0201KRX5R5BB104 | Multiple |  | Purchase | SMT | 54 | PCS | C333 C336 C341 C345 C349 C353 C354 C355 C359 C360 C361 C365 C366 C367 C368 C369 C370 C371 C372 C376 C377 C378 C379 C380 C381 C382 C383 C396 C397 C398 C399 C400 C401 C402 C403 C404 C405 C406 C407 C408 C409 C410 C411 C412 C413 C414 C415 C416 C417 C418 C419 C420 C421 C422 |
| 3 | B55.01107.M011 | 78.10421.2FL | CHIP CAP C 0.1U 16V K0402 X7R | R2_SA;HF_SA;G_SA; | DARFON;MURATA;PHYCOMP;SAMSUNG;TAIYO;WALSIN;YAGEO | C1005X7R104KET;GRM155R71C104KA88D;223878715649;CL05B104KO5NNNC;EMK105B7104KV-F;0402B104K160CT;CC0402KRX7R7BB104 | Multiple |  | Purchase | SMT | 106 | PCS | C1 C103 C126 C127 C130 C135 C136 C141 C169 C185 C195 C198 C203 C214 C227 C230 C239 C242 C251 C254 C27 C30 C323 C327 C328 C329 C33 C34 C36 C37 C38 C39 C41 C431 C432 C433 C434 C435 C436 C437 C438 C439 C44 C440 C441 C442 C443 C444 C445 C446 C447 C448 C449 C450 C451 C452 C453 C454 C455 C456 C457 C458 C459 C460 C467 C468 C469 C470 C471 C472 C481 C482 C483 C484 C485 C49 C502 C503 C504 C505 C506 C508 C51 C513 C514 C515 C516 C517 C521 C523 C55 C66 C67 C68 C69 C70 C71 C72 C73 C74 C75 C78 C79 C80 C93 C999 |
| 3 | B55.01107.M011 | 78.10422.2FL | CHIP CAP C 0.1U 25V K0402 X7R | R2_SA;HF_SA;G_SA; | YAGEO;WALSIN;MURATA;SAMSUNG;TAIYO;DARFON | CC0402KRX7R8BB104;0402B104K250CT;GRM155R71E104KE14D;CL05B104KA5NNNC;TMK105B7104KV-FR;C1005X7R104KFT | Multiple |  | Purchase | SMT | 17 | PCS | C117 C118 C119 C120 C121 C122 C123 C124 C125 C138 C181 C189 C221 C518 C519 C520 C522 |
| 3 | B55.01107.M011 | 78.10424.2BL | CHIP CAP C 0.1U 50V K0603 X7R | R2_SA;HF_SA;G_SA; | MURATA;AVX;PHYCOMP;SAMSUNG;DARFON;WALSIN;YAGEO | GRM188R71H104KA93D;06035C104KAT2A;223858615649;CL10B104KB8NNNC;C1608X7R104KGT;0603B104K500CT;CC0603KRX7R9BB104 | Multiple |  | Purchase | SMT | 11 | PCS | C139 C148 C149 C150 C158 C160 C178 C207 C263 C285 C288 |
| 3 | B55.01107.M011 | 78.10510.5SL | CHIP CAP C 1U 6.3V M0201 X5R | R2_SA;HF_SA;G_SA; | MURATA;DARFON;TAIYO;SAMSUNG;AVX;WALSIN;YAGEO | GRM033R60J105MEA2D;C0603X5R105MCT;JDK063BJ105MP-FD;CL03A105MQ3CSNH;CV03X5R105M06AH;0201X105M6R3;CC0201MRX5R5BB105 | Multiple |  | Purchase | SMT | 8 | PCS | C337 C340 C344 C348 C352 C358 C364 C375 |
| 3 | B55.01107.M011 | 78.10521.2BL | CHIP CAP C 1U 16V K0603 X7R | R2_SA;HF_SA;G_SA; | KEMET;MURATA;TAIYO;TDK;YAGEO;WALSIN;SAMSUNG;DARFON | C0603C105K4RAC;GRM188R71C105KA12D;EMK107B7105KA-T;C1608X7R1C105KT;CC0603KRX7R7BB105;0603B105K160CT;CL10B105KO8NNNC;C1608X7R105KET | Multiple |  | Purchase | SMT | 48 | PCS | C100 C101 C102 C107 C108 C109 C110 C113 C114 C13 C144 C145 C147 C15 C156 C16 C161 C18 C182 C19 C197 C2 C202 C209 C21 C22 C229 C241 C253 C26 C31 C54 C56 C58 C59 C60 C61 C62 C64 C65 C87 C90 C92 C95 C97 C98 C99 C998 |
| 3 | B55.01107.M011 | 78.10522.2BL | CHIP CAP C 1U 25V K0603 X7R | R2_SA;HF_SA;G_SA; | MURATA;TAIYO;WALSIN;SAMSUNG;DARFON;YAGEO | GRM188R71E105KA12D;TMK107B7105KA-T;0603B105K250CT;CL10B105KA8NNNC;C1608X7R105KFT;CC0603KRX7R8BB105 | Multiple |  | Purchase | SMT | 5 | PCS | C128 C267 C277 C278 C282 |
| 3 | B55.01107.M011 | 78.10620.21L | CHIP CAP C 10U 6.3V K0805 X7R | R2_SA;HF_SA;G_SA; | MURATA;TAIYO;DARFON;KYOCERA | GRM21BR70J106KE76L;JMK212B7106KG-T;C2012X7R106KC;CM21X7R106K06AT | Multiple |  | Purchase | SMT | 48 | PCS | C172 C174 C187 C188 C191 C192 C193 C194 C199 C200 C215 C216 C217 C218 C220 C223 C224 C225 C226 C231 C232 C235 C236 C237 C238 C243 C244 C247 C248 C249 C250 C255 C256 C331 C332 C335 C339 C343 C347 C351 C357 C384 C385 C386 C387 C388 C389 C57 |
| 3 | B55.01107.M011 | 78.10710.52L | CHIP CAP C 100U 6.3V M1206 X5R | R2_SA;HF_SA;G_SA; | MURATA;TAIYO;SAMSUNG;WALSIN | GRM31CR60J107ME39L;JMK316BJ107ML;CL31A107MQHNNNE;1206X107M6R3CT | Multiple |  | Purchase | SMT | 3 | PCS | C362 C373 C374 |
| 3 | B55.01107.M011 | 78.12034.1FL | CHIP CAP C 12P 50V J0402 NPO | R2_SA;HF_SA;G_SA; | AVX;MURATA;PHYCOMP;TAIYO;TDK;DARFON;MURATA;WALSIN;YAGEO | 04025A120JAT2A;GRM1555C1H120JZ01D;223886915129;UMK105CH120JW-F;C1005C0G1H120J;C1005NP0120JGT;GRM1555C1H120JA01D;0402N120J500CT;CC0402JRNPO9BN120 | Multiple |  | Purchase | SMT | 2 | PCS | C305 C306 |
| 3 | B55.01107.M011 | 78.15322.2FL | CHIP CAP C 0.015U 25V K0402 X7R | R2_SA;HF_SA;G_SA; | MURATA;TDK;WALSIN;DARFON;PHYCOMP | GRM155R71E153KA61D;C1005X7R1E153KT000F;0402B153K250CT;C1005X7R153KFT;223891715638 | Multiple |  | Purchase | SMT | 1 | PCS | C133 |
| 3 | B55.01107.M011 | 78.18034.1FL | CHIP CAP C 18P 50V J0402 NP0 | R2_SA;HF_SA;G_SA; | WALSIN;AVX;TDK;PHYCOMP;TAIYO;DARFON;MURATA | 0402N180J500CT;04025A180JAT2A;C1005C0G1H180JT;223886915189;UMK105CH180JV-F;C1005NP0180JGT;GRM1555C1H180JA01D | Multiple |  | Purchase | SMT | 2 | PCS | C17 C20 |
| 3 | B55.01107.M011 | 78.22124.2FL | CHIP CAP C 220P 50V K0402 X7R | R2_SA;HF_SA;G_SA; | MURATA;AVX;TAIYO;PHYCOMP;DARFON;WALSIN;YAGEO | GRM155R71H221KA01D;04025C221KAT2A;UMK105B7221KV-F;223858715614;C1005X7R221KGT;0402B221K500CT;CC0402KRX7R9BB221 | Multiple |  | Purchase | SMT | 1 | PCS | C281 |
| 3 | B55.01107.M011 | 78.22423.5SL | CHIP CAP C 0.22U 10V K0201 X5R | R2_SA;HF_SA;G_SA; | MURATA;DARFON;TAIYO;YAGEO;WALSIN;SAMSUNG | GRM033R61A224KE90D;C0603X5R224KDT;LMK063BJ224KP-F;CC0201KRX5R6BB224;0201X224K100CT;CL03A224KP3NNNC | Multiple |  | Purchase | SMT | 16 | PCS | C289 C290 C291 C292 C293 C294 C295 C296 C297 C298 C299 C300 C301 C302 C303 C304 |
| 3 | B55.01107.M011 | 78.22522.21L | CHIP CAP C 2.2U 25V K0805 X7R | R2_SA;HF_SA;G_SA; | WALSIN ; SAMSUNG ; PHYCOMP | 0805B225K250CT ; CL21B225KAFNNNE ; 222291015667 | Multiple |  | Purchase | SMT | 3 | PCS | C25 C28 C29 |
| 3 | B55.01107.M011 | 78.22620.22L | CHIP CAP C 22U 6.3V K 1206 X7R | R2_SA;HF_SA;G_SA; | YAGEO;MURATA;KYOCERA;SAMSUNG | CC1206KKX7R5BB226;GRM31CR70J226KE19L;CM316X7R226K06AT;CL31B226KQHNNNE | Multiple |  | Purchase | SMT | 9 | PCS | C258 C259 C260 C261 C264 C265 C266 C268 C283 |
| 3 | B55.01107.M011 | 78.22621.82L | CHIP CAP C 22UF 16V K1206 X6S | R2_SA;HF_SA; | MURATA;TAIYO;SAMSUNG | GRM31CC81C226KE15L;EMK316BC6226KL-T;CL31X226KOHN3NE | Multiple |  | Purchase | SMT | 1 | PCS | C132 |
| 3 | B55.01107.M011 | 78.33034.1FL | CHIP CAP 33P 50V J0402 NPO(ROHS | R2_SA;HF_SA;G_SA; | AVX;DARFON;MURATA;PHYCOMP;SAMSUNG;TAIYO;MURATA;WALSIN;YAGEO | 04025A330JAT2A;C1005NP0330JGT;GRM1555C1H330JZ01D;223886915339;CL05C330JB5NNNC;UMK105CH330JV-F;GRM1555C1H330JA01D;0402N330J500CT;CC0402JRNPO9BN330 | Multiple |  | Purchase | SMT | 1 | PCS | C82 |
| 3 | B55.01107.M011 | 78.33224.2FL | CHIP CAP C 3300P 50V K0402 X7R | R2_SA;HF_SA;G_SA; | MURATA;AVX;TAIYO;PHYCOMP;DARFON;WALSIN;YAGEO | GRM155R71H332KA01D;04025C332KAT2A;UMK105B7332KV-F;223858715629;C1005X7R332KGT;0402B332K500CT;CC0402KRX7R9BB332 | Multiple |  | Purchase | SMT | 1 | PCS | C208 |
| 3 | B55.01107.M011 | 78.33324.2BL | CHIP CAP 0.033U 50V K0603 X7R | R2_SA;HF_SA;G_SA; | MURATA;AVX;PHYCOMP;DARFON;YAGEO | GRM188R71H333KA61D;06035C333KAT2A;223858615643;C1608X7R333KGT;CC0603KRX7R9BB333 | Multiple |  | Purchase | SMT | 1 | PCS | C146 |
| 3 | B55.01107.M011 | 78.33421.2BL | CHIP CAP C 0.33U 16V K0603 X7R | R2_SA;HF_SA;G_SA; | MURATA;TDK;PHYCOMP;SAMSUNG;DARFON | GRM188R71C334KA01D;C1608X7R1C334KT000N;223878615656;CL10B334KO8NNNC;C1608X7R334KET | Multiple |  | Purchase | SMT | 1 | PCS | C286 |
| 3 | B55.01107.M011 | 78.47124.2FL | CHIP CAP C 470P  50V K0402 X7R | R2_SA;HF_SA;G_SA; | AVX;DARFON;MURATA;PHYCOMP;TAIYO;SAMSUNG;WALSIN;YAGEO | 04025C471KAT2A;C1005X7R471KGT;GRM155R71H471KA01D;223858715618;UMK105B7471KV-F;CL05B471KB5NNNC;0402B471K500CT;CC0402KRX7R9BB471 | Multiple |  | Purchase | SMT | 4 | PCS | C196 C228 C240 C252 |
| 3 | B55.01107.M011 | 78.47222.2FL | CHIP CAP C 4700P 25V K0402 X7R | R2_SA;HF_SA;G_SA; | AVX;TDK;PHYCOMP;TAIYO;DARFON;WALSIN | 04023C472KAT2A;C1005X7R1E472KT000F;223891715632;TMK105B7472KV-F;C1005X7R472KFT;0402B472K250CT | Multiple |  | Purchase | SMT | 1 | PCS | C276 |
| 3 | B55.01107.M011 | 78.47422.2BL | CHIP CAP C 0.47U 25V K0603 X7R | R2_SA;HF_SA;G_SA; | MURATA;SAMSUNG;DARFON | GRM188R71E474KA12D;CL10B474KA8NNNC;C1608X7R474KFT | Multiple |  | Purchase | SMT | 2 | PCS | C186 C219 |
| 3 | B55.01107.M011 | 78.68224.2FL | CHIP CAP C 6800P 50V K0402 X7R | R2_SA;HF_SA;G_SA; | YAGEO;MURATA;DARFON;SAMSUNG;WALSIN | CC0402KRX7R9BB682;GRM155R71H682KA88D;C1005X7R682KGT;CL05B682KB5NNNC;0402B682K500CT | Multiple |  | Purchase | SMT | 2 | PCS | C262 C279 |
| 3 | B55.01107.M011 | 79.47719.2BL | CHIP CAP 470UF 2V EEFSX0D471X | R2_SA;HF_SA;G_SA; | PANASONIC | EEFSX0D471XE | Multiple |  | Purchase | SMT | 2 | PCS | C324 C509 |
| A | B55.01107.M011 | 077.54771.0001 | CHIP AP CAP 470UF 2V M7343 ESR6 | R2_SA;HF_SA; | APAQ | ACAH2R0S471E06 |  |  | Purchase |  |  |  |  |
| 3 | B55.01107.M011 | 82.20043.221 | OSC 50MHZ 15P50PPM HXO-SC SMD | R2_SA;HF_SA; | HOSONIC | DSCB50.0000MTS | Multiple |  | Purchase | SMT | 1 | PCS | X2 |
| A | B55.01107.M011 | 82.20043.191 | OSC 50MHZ 50PPM 3.3V HSO321S | R2_SA;HF_SA; | HARMONY | SSW050000I3CH-S |  |  | Purchase |  |  |  |  |
| 3 | B55.01107.M011 | 82.30004.901 | XTAL 24MHZ 12PF20PPM HCX-3SB SMD | R2_SA;HF_SA; | HOSONIC | E3SB24.0000F12M22 | Multiple |  | Purchase | SMT | 1 | PCS | X1 |
| A | B55.01107.M011 | 82.30004.771 | XTAL 24MHZ 12P 30PPM HSX321S SMD | R2_SA;HF_SA; | HARMONY | X3S024000FC1H-HV |  |  | Purchase |  |  |  |  |
| 3 | B55.01107.M011 | 83.0005V.MAF | DIODE ESD PESD5V0F1BL,315 SOD882 | R2_SA;HF_SA; | NXP | PESD5V0F1BL,315 | Single |  | Purchase | SMT | 2 | PCS | D18 D19 |
| 3 | B55.01107.M011 | 83.01921.S70 | LED YEL GRN 19-21/G6C-BM2P1B/3T SMD | R2_SA;HF_SA;G_SA; | EVERLIGHT | 19-21/G6C-BM2P1B/3T | Single |  | Purchase | SMT | 3 | PCS | LED4 LED5 LED6 |
| 3 | B55.01107.M011 | 83.R2003.K8F | DIODE S.B BAT54WS-7-F SOD-323 | R2_SA;HF_SA; | DIODES | BAT54WS-7-F | Multiple |  | Purchase | SMT | 1 | PCS | D11 |
| A | B55.01107.M011 | 083.00054.0A8F | DIODE S.B LBAT54HT1G SOD-323 | R2_SA;HF_SA; | LRC | LBAT54HT1G |  |  | Purchase |  |  |  |  |
| A | B55.01107.M011 | 83.2R004.A8F | DIODE S.B SD103AWS SOD-323 | R2_SA;HF_SA; | YEASHIN | SD103AWS |  |  | Purchase |  |  |  |  |
| 3 | B55.01107.M011 | 83.SMF15.0AH | DIODE TVS SMF15A SOD-123FL | R2_SA;HF_SA; | PANJIT | SMF15A | Multiple |  | Purchase | SMT | 1 | PCS | D1 |
| A | B55.01107.M011 | 83.00015.0AF | DIODE TVS DFLT15A-7 POWERDI123 | R2_SA;HF_SA; | DIODES | DFLT15A-7 |  |  | Purchase |  |  |  |  |
| 3 | B55.01107.M011 | 84.03904.T11 | XTOR MMBT3904 NPN SOT-23 | R2_SA;HF_SA;G_SA; | PANJIT | MMBT3904 | Multiple |  | Purchase | SMT | 3 | PCS | PQ1 Q2 Q3 |
| A | B55.01107.M011 | 84.03904.L06 | XTOR PMBS3904,215 NPN SOT23 (GP) | R2_SA;HF_SA;G_SA; | NEXPERIA | PMBS3904,215 |  |  | Purchase |  |  |  |  |
| A | B55.01107.M011 | 84.T3904.H11 | XTOR LMBT3904LT1G NPN SOT-23 | R2_SA;HF_SA;G_SA; | LRC | LMBT3904LT1G |  |  | Purchase |  |  |  |  |
| 3 | B55.01107.M011 | 84.08878.A37 | FET MOS FDS8878_G NC SO-8(HF) | R2_SA;HF_SA; | FAIRCHILD | FDS8878_G | Multiple |  | Purchase | SMT | 2 | PCS | PQ3 PQ5 |
| A | B55.01107.M011 | 84.04172.037 | FET MOS SI4172DY-T1-GE3 NC SO8 | R2_SA;HF_SA; | VISHAY | SI4172DY-T1-GE3 |  |  | Purchase |  |  |  |  |
| 3 | B55.01107.M011 | 84.2N702.031 | FET MOS 2N7002K-7 NC SOT-23 2KV 300MA | R2_SA;HF_SA; | DIODES | 2N7002K-7 | Multiple |  | Purchase | SMT | 14 | PCS | PQ2 PQ4 Q11 Q12 Q16 Q17 Q20 Q25 Q26 Q29 Q4 Q6 Q7 Q8 |
| A | B55.01107.M011 | 84.2N702.J31 | FET MOS 2N7002K NC SOT-23 ESD 2KV 300MA | R2_SA;HF_SA;G_SA; | PANJIT | 2N7002K |  |  | Purchase |  |  |  |  |
| 3 | B55.01107.M011 | B48.01127.0021 | PCB 16318-2 BRYCE CANYON IOM(W/ IOC)8L G | R2_SA;HF_SA; | GCE | B48.01127.0021 | Multiple |  | Purchase | SMT | 1 | PCS | PCBL |
| A | B55.01107.M011 | B48.01148.0021 | PCB 16318-2 BRYCE CANYON IOM(W/ IOC)8L T | R2_SA;HF_SA; | TRIPOD | B48.01148.0021 |  |  | Purchase |  |  |  |  |
| 3 | B55.01107.M011 | BZA.01101.0052 | BRYCE CANYON IOC F/W MODULE FOR IOM | R2; |  |  |  | M | Manufacture | SMT | 1 | PCS | FW |
| 4 | BZA.01101.0052 | 072.29128.0F09 | IC FEROM MX29GL128FDT2I-11G TSOP 56P | R2_SA;HF_SA; | MXIC | MX29GL128FDT2I-11G | Multiple |  | Purchase |  | 1 | PCS | U42 |
| A | BZA.01101.0052 | 72.29128.Z09 | IC FEROM S29GL128S10TFIV20 TSOP 56P | R2_SA;HF_SA; | SPANSION | S29GL128S10TFIV20 |  |  | Purchase |  |  |  |  |
| 4 | BZA.01101.0052 | B53.01101.0071 | F/W IOC OFFLINE 13_00_0B022701 | R2; | TBD |  | Single |  | Manufacture |  | 1 | PCS |  |
| 3 | B55.01107.M011 | BZA.01101.0054 | BRYCE CANYON IOC EEPROM MODULE FOR IOM | R2; |  |  |  | M | Manufacture | SMT | 1 | PCS | FW |
| 4 | BZA.01101.0054 | 72.24C64.I01 | IC EEPROM CAT24C64WI-GT3 SOIC 8P | R2_SA;HF_SA;G_SA; | ON | CAT24C64WI-GT3 | Multiple |  | Purchase |  | 1 | PCS | U38 |
| A | BZA.01101.0054 | 72.24C64.K01 | IC EEPROM M24C64-RMN6TP SOIC 8P | R2_SA;HF_SA; | STMICROELECTRONICS INC | M24C64-RMN6TP |  |  | Purchase |  |  |  |  |
| 4 | BZA.01101.0054 | B53.01101.0081 | F/W IOC EEPROM 3008_FORTN | R2; | TBD |  | Single |  | Manufacture |  | 1 | PCS |  |
| 2 | B55.01107.0011 | B60.0110V.0011 | ASSY NIC CARD LATCH BC MP | R2_SA;HF_SA; | FIVETECH | TBD | Single | M | Purchase | DIP | 2 | PCS |  |
| 2 | B55.01107.0011 | BZA.01101.0055 | BRYCE CANYON NEW BMC F/W MODULE2 | R2; |  |  |  | M | Manufacture | DIP | 1 | PCS | FW |
| 3 | BZA.01101.0055 | 72.25635.A01 | IC FEROM MX25L25635FMI-10G SOP 16P | R2_SA;HF_SA; | MXIC | MX25L25635FMI-10G | Single |  | Purchase |  | 2 | PCS | U11 U29 |
| 3 | BZA.01101.0055 | B53.01101.00C1 | F/W BMC BRYCECANYON WBM_1.4.0 | R2; | TBD |  | Single |  | Manufacture |  | 1 | PCS |  |
